# BASEBOARD_FAB2 (Tioga Pass) — schematic netlist excerpt (pin names and nets, part order shuffled) for the footprints in the layout excerpt that follows; sources: Cadence DE-HDL packaged netlist, KiCad conversion of Wiwynn_Tioga_Pass_MB.brd

R1U39  RES  5.11K 1% CHIP  pkg 0402  page 169 : A = P3V3_STBY ; B = A_P3V3_STBY_SCALED
R25W133  RES  33.2 1% CHIP  pkg 0402  page 252 : A = I2C_BMC_VGA_DDC_SCL_G ; B = V_IBMC_5V_DDC_SCL_J
C2M5  CAP  10UF 4V 20% X6S  pkg 0603LF  page 127 : A = P1V05_PCH_STBY_WM20_PLL ; B = GND

(kicad_pcb
	(version 20260206)
	(generator "pcbnew")
	(generator_version "10.0")
	(general
		(thickness 1.6)
		(legacy_teardrops no)
	)
	(paper "A4")
	(title_block
		(title "Wiwynn_Tioga_Pass_MB.brd")
		(comment 1 "Tioga Pass / footprints 3489-3491 of 4770")
	)
	(layers
		(0 "F.Cu" signal "TOP")
		(4 "In1.Cu" signal "L2GND")
		(6 "In2.Cu" signal "L3")
		(8 "In3.Cu" signal "L4GND")
		(10 "In4.Cu" signal "L5")
		(12 "In5.Cu" signal "L6GND")
		(14 "In6.Cu" signal "L7VCC")
		(16 "In7.Cu" signal "L8VCC")
		(18 "In8.Cu" signal "L9GND")
		(20 "In9.Cu" signal "L10")
		(22 "In10.Cu" signal "L11GND")
		(24 "In11.Cu" signal "L12")
		(26 "In12.Cu" signal "L13GND")
		(2 "B.Cu" signal "BOTTOM")
		(9 "F.Adhes" user "F.Adhesive")
		(11 "B.Adhes" user "B.Adhesive")
		(13 "F.Paste" user "Package Geometry/Pastemask Top")
		(15 "B.Paste" user "Package Geometry/Pastemask Bottom")
		(5 "F.SilkS" user "Ref Des/Silkscreen Top")
		(7 "B.SilkS" user "Ref Des/Silkscreen Bottom")
		(1 "F.Mask" user "Board Geometry/Soldermask Top")
		(3 "B.Mask" user "Board Geometry/Soldermask Bottom")
		(17 "Dwgs.User" user "User.Drawings")
		(19 "Cmts.User" user "User.Comments")
		(21 "Eco1.User" user "User.Eco1")
		(23 "Eco2.User" user "User.Eco2")
		(25 "Edge.Cuts" user "Board Geometry/Outline")
		(27 "Margin" user)
		(31 "F.CrtYd" user "Package Geometry/Place Bound Top")
		(29 "B.CrtYd" user "Package Geometry/Place Bound Bottom")
		(35 "F.Fab" user "Ref Des/Assembly Top")
		(33 "B.Fab" user "Ref Des/Assembly Bottom")
	)
	(footprint ""
		(layer "B.Cu")
		(at 494.712244 -47.503588 180)
		(property "Reference" "R25W133"
			(at 0.8382 -0.67818 180)
			(unlocked yes)
			(layer "B.SilkS")
			(effects
				(font
					(size 0.4064 0.254)
					(thickness 0.1524)
				)
				(justify left mirror)
			)
		)
		(property "Value" ""
			(at 0 0 0)
			(layer "B.Fab")
			(effects
				(font
					(size 1.27 1.27)
				)
				(justify mirror)
			)
		)
		(duplicate_pad_numbers_are_jumpers no)
		(fp_poly
			(pts
				(xy 0.2794 -0.1016) (xy -0.2794 -0.1016) (xy -0.2794 0.9906) (xy 0.2794 0.9906)
			)
			(stroke
				(width 0)
				(type default)
			)
			(fill no)
			(layer "B.CrtYd")
		)
		(fp_line
			(start 0.2794 0.9906)
			(end -0.2794 0.9906)
			(stroke
				(width 0.1)
				(type default)
			)
			(layer "B.Fab")
		)
		(fp_line
			(start 0.2794 -0.1016)
			(end 0.2794 0.9906)
			(stroke
				(width 0.1)
				(type default)
			)
			(layer "B.Fab")
		)
		(fp_line
			(start -0.2794 0.9906)
			(end -0.2794 -0.1016)
			(stroke
				(width 0.1)
				(type default)
			)
			(layer "B.Fab")
		)
		(fp_line
			(start -0.2794 -0.1016)
			(end 0.2794 -0.1016)
			(stroke
				(width 0.1)
				(type default)
			)
			(layer "B.Fab")
		)
		(pad "1" smd rect
			(at 0 0)
			(size 0.508 0.508)
			(layers "B.Cu" "B.Mask" "B.Paste")
			(net "I2C_BMC_VGA_DDC_SCL_G")
		)
		(pad "2" smd rect
			(at 0 0.889)
			(size 0.508 0.508)
			(layers "B.Cu" "B.Mask" "B.Paste")
			(net "V_IBMC_5V_DDC_SCL_J")
		)
		(zone
			(layer "B.Cu")
			(hatch none 0.5)
			(connect_pads
				(clearance 0)
			)
			(min_thickness 0.25)
			(keepout
				(tracks not_allowed)
				(vias allowed)
				(pads allowed)
				(copperpour not_allowed)
				(footprints allowed)
			)
			(placement
				(enabled no)
				(sheetname "")
			)
			(fill
				(thermal_gap 0.5)
				(thermal_bridge_width 0.5)
				(island_removal_mode 0)
			)
			(polygon
				(pts
					(xy 494.458244 -48.138588) (xy 494.966244 -48.138588) (xy 494.966244 -47.757588) (xy 494.458244 -47.757588)
				)
			)
		)
		(zone
			(layer "B.Cu")
			(hatch none 0.5)
			(connect_pads
				(clearance 0)
			)
			(min_thickness 0.25)
			(keepout
				(tracks allowed)
				(vias not_allowed)
				(pads allowed)
				(copperpour not_allowed)
				(footprints allowed)
			)
			(placement
				(enabled no)
				(sheetname "")
			)
			(fill
				(thermal_gap 0.5)
				(thermal_bridge_width 0.5)
				(island_removal_mode 0)
			)
			(polygon
				(pts
					(xy 494.458244 -47.757588) (xy 494.966244 -47.757588) (xy 494.966244 -48.138588) (xy 494.458244 -48.138588)
				)
			)
		)
	)
	(footprint ""
		(layer "B.Cu")
		(at 404.101046 -25.600152 180)
		(property "Reference" "R1U39"
			(at 0 0 0)
			(layer "B.SilkS")
			(hide yes)
			(effects
				(font
					(size 1.27 1.27)
				)
				(justify mirror)
			)
		)
		(property "Value" ""
			(at 0 0 0)
			(layer "B.Fab")
			(effects
				(font
					(size 1.27 1.27)
				)
				(justify mirror)
			)
		)
		(duplicate_pad_numbers_are_jumpers no)
		(fp_poly
			(pts
				(xy 0.2794 -0.1016) (xy -0.2794 -0.1016) (xy -0.2794 0.9906) (xy 0.2794 0.9906)
			)
			(stroke
				(width 0)
				(type default)
			)
			(fill no)
			(layer "B.CrtYd")
		)
		(fp_line
			(start 0.2794 0.9906)
			(end -0.2794 0.9906)
			(stroke
				(width 0.1)
				(type default)
			)
			(layer "B.Fab")
		)
		(fp_line
			(start 0.2794 -0.1016)
			(end 0.2794 0.9906)
			(stroke
				(width 0.1)
				(type default)
			)
			(layer "B.Fab")
		)
		(fp_line
			(start -0.2794 0.9906)
			(end -0.2794 -0.1016)
			(stroke
				(width 0.1)
				(type default)
			)
			(layer "B.Fab")
		)
		(fp_line
			(start -0.2794 -0.1016)
			(end 0.2794 -0.1016)
			(stroke
				(width 0.1)
				(type default)
			)
			(layer "B.Fab")
		)
		(pad "1" smd rect
			(at 0 0)
			(size 0.508 0.508)
			(layers "B.Cu" "B.Mask" "B.Paste")
			(net "P3V3_STBY")
		)
		(pad "2" smd rect
			(at 0 0.889)
			(size 0.508 0.508)
			(layers "B.Cu" "B.Mask" "B.Paste")
			(net "A_P3V3_STBY_SCALED")
		)
		(zone
			(layer "B.Cu")
			(hatch none 0.5)
			(connect_pads
				(clearance 0)
			)
			(min_thickness 0.25)
			(keepout
				(tracks not_allowed)
				(vias allowed)
				(pads allowed)
				(copperpour not_allowed)
				(footprints allowed)
			)
			(placement
				(enabled no)
				(sheetname "")
			)
			(fill
				(thermal_gap 0.5)
				(thermal_bridge_width 0.5)
				(island_removal_mode 0)
			)
			(polygon
				(pts
					(xy 403.847046 -26.235152) (xy 404.355046 -26.235152) (xy 404.355046 -25.854152) (xy 403.847046 -25.854152)
				)
			)
		)
		(zone
			(layer "B.Cu")
			(hatch none 0.5)
			(connect_pads
				(clearance 0)
			)
			(min_thickness 0.25)
			(keepout
				(tracks allowed)
				(vias not_allowed)
				(pads allowed)
				(copperpour not_allowed)
				(footprints allowed)
			)
			(placement
				(enabled no)
				(sheetname "")
			)
			(fill
				(thermal_gap 0.5)
				(thermal_bridge_width 0.5)
				(island_removal_mode 0)
			)
			(polygon
				(pts
					(xy 403.847046 -25.854152) (xy 404.355046 -25.854152) (xy 404.355046 -26.235152) (xy 403.847046 -26.235152)
				)
			)
		)
	)
	(footprint ""
		(layer "B.Cu")
		(at 409.1432 -123.6218 90)
		(property "Reference" "C2M5"
			(at 0 0 90)
			(layer "B.SilkS")
			(hide yes)
			(effects
				(font
					(size 1.27 1.27)
				)
				(justify mirror)
			)
		)
		(property "Value" ""
			(at 0 0 90)
			(layer "B.Fab")
			(effects
				(font
					(size 1.27 1.27)
				)
				(justify mirror)
			)
		)
		(duplicate_pad_numbers_are_jumpers no)
		(fp_poly
			(pts
				(xy 0.4953 -0.2032) (xy -0.4953 -0.2032) (xy -0.4953 1.6002) (xy 0.4953 1.6002)
			)
			(stroke
				(width 0)
				(type default)
			)
			(fill no)
			(layer "B.CrtYd")
		)
		(fp_line
			(start 0.4953 -0.2032)
			(end -0.4953 -0.2032)
			(stroke
				(width 0.1)
				(type default)
			)
			(layer "B.Fab")
		)
		(fp_line
			(start -0.4953 -0.2032)
			(end -0.4953 1.6002)
			(stroke
				(width 0.1)
				(type default)
			)
			(layer "B.Fab")
		)
		(fp_line
			(start 0.4953 1.6002)
			(end 0.4953 -0.2032)
			(stroke
				(width 0.1)
				(type default)
			)
			(layer "B.Fab")
		)
		(fp_line
			(start -0.4953 1.6002)
			(end 0.4953 1.6002)
			(stroke
				(width 0.1)
				(type default)
			)
			(layer "B.Fab")
		)
		(pad "1" smd rect
			(at 0 0 270)
			(size 0.762 0.889)
			(layers "B.Cu" "B.Mask" "B.Paste")
			(net "P1V05_PCH_STBY_WM20_PLL")
		)
		(pad "2" smd rect
			(at 0 1.397 270)
			(size 0.762 0.889)
			(layers "B.Cu" "B.Mask" "B.Paste")
			(net "GND")
		)
		(zone
			(layer "B.Cu")
			(hatch none 0.5)
			(connect_pads
				(clearance 0)
			)
			(min_thickness 0.25)
			(keepout
				(tracks not_allowed)
				(vias allowed)
				(pads allowed)
				(copperpour not_allowed)
				(footprints allowed)
			)
			(placement
				(enabled no)
				(sheetname "")
			)
			(fill
				(thermal_gap 0.5)
				(thermal_bridge_width 0.5)
				(island_removal_mode 0)
			)
			(polygon
				(pts
					(xy 409.5877 -124.0028) (xy 409.5877 -123.2408) (xy 410.0957 -123.2408) (xy 410.0957 -124.0028)
				)
			)
		)
	)
)
